(kicad_pcb
	(version 20260206)
	(generator "pcbnew")
	(generator_version "10.0")
	(general
		(thickness 1.6)
		(legacy_teardrops no)
	)
	(paper "A4")
	(title_block
		(title "04192023_DAF0TMB3IC0_F0TG_MB_C_brd_V02_OCP.brd")
		(comment 1 "Grand Teton / footprints 3498-3504 of 8354")
	)
	(layers
		(0 "F.Cu" signal "TOP")
		(4 "In1.Cu" signal "GND")
		(6 "In2.Cu" signal "IN1")
		(8 "In3.Cu" signal "GND1")
		(10 "In4.Cu" signal "IN2")
		(12 "In5.Cu" signal "GND2")
		(14 "In6.Cu" signal "IN3")
		(16 "In7.Cu" signal "GND3")
		(18 "In8.Cu" signal "VCC")
		(20 "In9.Cu" signal "VCC1")
		(22 "In10.Cu" signal "GND4")
		(24 "In11.Cu" signal "IN4")
		(26 "In12.Cu" signal "GND5")
		(28 "In13.Cu" signal "IN5")
		(30 "In14.Cu" signal "GND6")
		(32 "In15.Cu" signal "IN6")
		(34 "In16.Cu" signal "GND7")
		(2 "B.Cu" signal "BOTTOM")
		(9 "F.Adhes" user "F.Adhesive")
		(11 "B.Adhes" user "B.Adhesive")
		(13 "F.Paste" user "Package Geometry/Pastemask Top")
		(15 "B.Paste" user "Package Geometry/Pastemask Bottom")
		(5 "F.SilkS" user "Ref Des/Silkscreen Top")
		(7 "B.SilkS" user "Ref Des/Silkscreen Bottom")
		(1 "F.Mask" user "Board Geometry/Soldermask Top")
		(3 "B.Mask" user "Board Geometry/Soldermask Bottom")
		(17 "Dwgs.User" user "User.Drawings")
		(19 "Cmts.User" user "User.Comments")
		(21 "Eco1.User" user "User.Eco1")
		(23 "Eco2.User" user "User.Eco2")
		(25 "Edge.Cuts" user "Board Geometry/Outline")
		(27 "Margin" user)
		(31 "F.CrtYd" user "Package Geometry/Place Bound Top")
		(29 "B.CrtYd" user "Package Geometry/Place Bound Bottom")
		(35 "F.Fab" user "Ref Des/Assembly Top")
		(33 "B.Fab" user "Ref Des/Assembly Bottom")
	)
	(footprint ""
		(layer "F.Cu")
		(at 341.578184 -172.311822 180)
		(property "Reference" "PR294"
			(at 0 0 180)
			(layer "F.SilkS")
			(hide yes)
			(effects
				(font
					(size 1.27 1.27)
				)
			)
		)
		(property "Value" ""
			(at 0 0 180)
			(layer "F.Fab")
			(effects
				(font
					(size 1.27 1.27)
				)
			)
		)
		(duplicate_pad_numbers_are_jumpers no)
		(fp_line
			(start 0.7874 0.4064)
			(end -0.7874 0.4064)
			(stroke
				(width 0.1524)
				(type default)
			)
			(layer "F.SilkS")
		)
		(fp_line
			(start 0.7874 -0.4064)
			(end 0.7874 0.4064)
			(stroke
				(width 0.1524)
				(type default)
			)
			(layer "F.SilkS")
		)
		(fp_line
			(start -0.7874 0.4064)
			(end -0.7874 -0.4064)
			(stroke
				(width 0.1524)
				(type default)
			)
			(layer "F.SilkS")
		)
		(fp_line
			(start -0.7874 -0.4064)
			(end 0.7874 -0.4064)
			(stroke
				(width 0.1524)
				(type default)
			)
			(layer "F.SilkS")
		)
		(fp_line
			(start 0.67945 0.3048)
			(end 0.120396 0.3048)
			(stroke
				(width 0.1)
				(type default)
			)
			(layer "F.Fab")
		)
		(fp_line
			(start 0.67945 -0.3048)
			(end 0.67945 0.3048)
			(stroke
				(width 0.1)
				(type default)
			)
			(layer "F.Fab")
		)
		(fp_line
			(start 0.12065 -0.2794)
			(end 0.12065 -0.3048)
			(stroke
				(width 0.1)
				(type default)
			)
			(layer "F.Fab")
		)
		(fp_line
			(start 0.12065 -0.3048)
			(end 0.67945 -0.3048)
			(stroke
				(width 0.1)
				(type default)
			)
			(layer "F.Fab")
		)
		(fp_line
			(start 0.120396 0.3048)
			(end 0.120396 0.2794)
			(stroke
				(width 0.1)
				(type default)
			)
			(layer "F.Fab")
		)
		(fp_line
			(start 0.120396 0.2794)
			(end -0.12065 0.2794)
			(stroke
				(width 0.1)
				(type default)
			)
			(layer "F.Fab")
		)
		(fp_line
			(start -0.12065 0.3048)
			(end -0.67945 0.3048)
			(stroke
				(width 0.1)
				(type default)
			)
			(layer "F.Fab")
		)
		(fp_line
			(start -0.12065 0.2794)
			(end -0.12065 0.3048)
			(stroke
				(width 0.1)
				(type default)
			)
			(layer "F.Fab")
		)
		(fp_line
			(start -0.12065 -0.2794)
			(end 0.12065 -0.2794)
			(stroke
				(width 0.1)
				(type default)
			)
			(layer "F.Fab")
		)
		(fp_line
			(start -0.12065 -0.305054)
			(end -0.12065 -0.2794)
			(stroke
				(width 0.1)
				(type default)
			)
			(layer "F.Fab")
		)
		(fp_line
			(start -0.67945 0.3048)
			(end -0.67945 -0.305054)
			(stroke
				(width 0.1)
				(type default)
			)
			(layer "F.Fab")
		)
		(fp_line
			(start -0.67945 -0.305054)
			(end -0.12065 -0.305054)
			(stroke
				(width 0.1)
				(type default)
			)
			(layer "F.Fab")
		)
		(pad "1" smd circle
			(at -0.40005 0 180)
			(size 0 0)
			(layers "F.Cu" "F.Mask" "F.Paste")
			(net "PVDDCR_CPU0_P0")
		)
		(pad "2" smd circle
			(at 0.40005 0 180)
			(size 0 0)
			(layers "F.Cu" "F.Mask" "F.Paste")
			(net "VSENSE_PVDDCR_CPU0_P0_DP")
		)
	)
	(footprint ""
		(layer "F.Cu")
		(at 342.966294 -161.056574 90)
		(property "Reference" "PC153_6"
			(at 0 0 90)
			(layer "F.SilkS")
			(hide yes)
			(effects
				(font
					(size 1.27 1.27)
				)
			)
		)
		(property "Value" ""
			(at 0 0 90)
			(layer "F.Fab")
			(effects
				(font
					(size 1.27 1.27)
				)
			)
		)
		(duplicate_pad_numbers_are_jumpers no)
		(fp_line
			(start 0.7874 -0.4064)
			(end 0.7874 0.4064)
			(stroke
				(width 0.1524)
				(type default)
			)
			(layer "F.SilkS")
		)
		(fp_line
			(start -0.7874 -0.4064)
			(end 0.7874 -0.4064)
			(stroke
				(width 0.1524)
				(type default)
			)
			(layer "F.SilkS")
		)
		(fp_line
			(start 0.7874 0.4064)
			(end -0.7874 0.4064)
			(stroke
				(width 0.1524)
				(type default)
			)
			(layer "F.SilkS")
		)
		(fp_line
			(start -0.7874 0.4064)
			(end -0.7874 -0.4064)
			(stroke
				(width 0.1524)
				(type default)
			)
			(layer "F.SilkS")
		)
		(fp_line
			(start -0.12065 -0.305054)
			(end -0.12065 -0.2794)
			(stroke
				(width 0.1)
				(type default)
			)
			(layer "F.Fab")
		)
		(fp_line
			(start -0.67945 -0.305054)
			(end -0.12065 -0.305054)
			(stroke
				(width 0.1)
				(type default)
			)
			(layer "F.Fab")
		)
		(fp_line
			(start 0.67945 -0.3048)
			(end 0.67945 0.3048)
			(stroke
				(width 0.1)
				(type default)
			)
			(layer "F.Fab")
		)
		(fp_line
			(start 0.12065 -0.3048)
			(end 0.67945 -0.3048)
			(stroke
				(width 0.1)
				(type default)
			)
			(layer "F.Fab")
		)
		(fp_line
			(start 0.12065 -0.2794)
			(end 0.12065 -0.3048)
			(stroke
				(width 0.1)
				(type default)
			)
			(layer "F.Fab")
		)
		(fp_line
			(start -0.12065 -0.2794)
			(end 0.12065 -0.2794)
			(stroke
				(width 0.1)
				(type default)
			)
			(layer "F.Fab")
		)
		(fp_line
			(start 0.120396 0.2794)
			(end -0.12065 0.2794)
			(stroke
				(width 0.1)
				(type default)
			)
			(layer "F.Fab")
		)
		(fp_line
			(start -0.12065 0.2794)
			(end -0.12065 0.3048)
			(stroke
				(width 0.1)
				(type default)
			)
			(layer "F.Fab")
		)
		(fp_line
			(start 0.67945 0.3048)
			(end 0.120396 0.3048)
			(stroke
				(width 0.1)
				(type default)
			)
			(layer "F.Fab")
		)
		(fp_line
			(start 0.120396 0.3048)
			(end 0.120396 0.2794)
			(stroke
				(width 0.1)
				(type default)
			)
			(layer "F.Fab")
		)
		(fp_line
			(start -0.12065 0.3048)
			(end -0.67945 0.3048)
			(stroke
				(width 0.1)
				(type default)
			)
			(layer "F.Fab")
		)
		(fp_line
			(start -0.67945 0.3048)
			(end -0.67945 -0.305054)
			(stroke
				(width 0.1)
				(type default)
			)
			(layer "F.Fab")
		)
		(pad "1" smd circle
			(at -0.40005 0 90)
			(size 0 0)
			(layers "F.Cu" "F.Mask" "F.Paste")
			(net "SW_P12V_AUX_PVDDCR_CPU0_P0_FLT")
		)
		(pad "2" smd circle
			(at 0.40005 0 90)
			(size 0 0)
			(layers "F.Cu" "F.Mask" "F.Paste")
			(net "GND")
		)
	)
	(footprint ""
		(layer "F.Cu")
		(at 166.624 -131.953 -90)
		(property "Reference" "R492"
			(at 0 0 270)
			(layer "F.SilkS")
			(hide yes)
			(effects
				(font
					(size 1.27 1.27)
				)
			)
		)
		(property "Value" ""
			(at 0 0 270)
			(layer "F.Fab")
			(effects
				(font
					(size 1.27 1.27)
				)
			)
		)
		(duplicate_pad_numbers_are_jumpers no)
		(fp_line
			(start -0.7874 0.4064)
			(end -0.7874 -0.4064)
			(stroke
				(width 0.1524)
				(type default)
			)
			(layer "F.SilkS")
		)
		(fp_line
			(start 0.7874 0.4064)
			(end -0.7874 0.4064)
			(stroke
				(width 0.1524)
				(type default)
			)
			(layer "F.SilkS")
		)
		(fp_line
			(start -0.7874 -0.4064)
			(end 0.7874 -0.4064)
			(stroke
				(width 0.1524)
				(type default)
			)
			(layer "F.SilkS")
		)
		(fp_line
			(start 0.7874 -0.4064)
			(end 0.7874 0.4064)
			(stroke
				(width 0.1524)
				(type default)
			)
			(layer "F.SilkS")
		)
		(fp_line
			(start -0.67945 0.3048)
			(end -0.67945 -0.305054)
			(stroke
				(width 0.1)
				(type default)
			)
			(layer "F.Fab")
		)
		(fp_line
			(start -0.12065 0.3048)
			(end -0.67945 0.3048)
			(stroke
				(width 0.1)
				(type default)
			)
			(layer "F.Fab")
		)
		(fp_line
			(start 0.120396 0.3048)
			(end 0.120396 0.2794)
			(stroke
				(width 0.1)
				(type default)
			)
			(layer "F.Fab")
		)
		(fp_line
			(start 0.67945 0.3048)
			(end 0.120396 0.3048)
			(stroke
				(width 0.1)
				(type default)
			)
			(layer "F.Fab")
		)
		(fp_line
			(start -0.12065 0.2794)
			(end -0.12065 0.3048)
			(stroke
				(width 0.1)
				(type default)
			)
			(layer "F.Fab")
		)
		(fp_line
			(start 0.120396 0.2794)
			(end -0.12065 0.2794)
			(stroke
				(width 0.1)
				(type default)
			)
			(layer "F.Fab")
		)
		(fp_line
			(start -0.12065 -0.2794)
			(end 0.12065 -0.2794)
			(stroke
				(width 0.1)
				(type default)
			)
			(layer "F.Fab")
		)
		(fp_line
			(start 0.12065 -0.2794)
			(end 0.12065 -0.3048)
			(stroke
				(width 0.1)
				(type default)
			)
			(layer "F.Fab")
		)
		(fp_line
			(start 0.12065 -0.3048)
			(end 0.67945 -0.3048)
			(stroke
				(width 0.1)
				(type default)
			)
			(layer "F.Fab")
		)
		(fp_line
			(start 0.67945 -0.3048)
			(end 0.67945 0.3048)
			(stroke
				(width 0.1)
				(type default)
			)
			(layer "F.Fab")
		)
		(fp_line
			(start -0.67945 -0.305054)
			(end -0.12065 -0.305054)
			(stroke
				(width 0.1)
				(type default)
			)
			(layer "F.Fab")
		)
		(fp_line
			(start -0.12065 -0.305054)
			(end -0.12065 -0.2794)
			(stroke
				(width 0.1)
				(type default)
			)
			(layer "F.Fab")
		)
		(pad "1" smd circle
			(at -0.40005 0 270)
			(size 0 0)
			(layers "F.Cu" "F.Mask" "F.Paste")
			(net "P3V3_AUX")
		)
		(pad "2" smd circle
			(at 0.40005 0 270)
			(size 0 0)
			(layers "F.Cu" "F.Mask" "F.Paste")
			(net "PWRGD_P5V_R_N")
		)
	)
	(footprint ""
		(layer "F.Cu")
		(at 194.911472 -422.671748 90)
		(property "Reference" "R8102"
			(at 0 0 90)
			(layer "F.SilkS")
			(hide yes)
			(effects
				(font
					(size 1.27 1.27)
				)
			)
		)
		(property "Value" ""
			(at 0 0 90)
			(layer "F.Fab")
			(effects
				(font
					(size 1.27 1.27)
				)
			)
		)
		(duplicate_pad_numbers_are_jumpers no)
		(fp_line
			(start 0.7874 -0.4064)
			(end 0.7874 0.4064)
			(stroke
				(width 0.1524)
				(type default)
			)
			(layer "F.SilkS")
		)
		(fp_line
			(start -0.7874 -0.4064)
			(end 0.7874 -0.4064)
			(stroke
				(width 0.1524)
				(type default)
			)
			(layer "F.SilkS")
		)
		(fp_line
			(start 0.7874 0.4064)
			(end -0.7874 0.4064)
			(stroke
				(width 0.1524)
				(type default)
			)
			(layer "F.SilkS")
		)
		(fp_line
			(start -0.7874 0.4064)
			(end -0.7874 -0.4064)
			(stroke
				(width 0.1524)
				(type default)
			)
			(layer "F.SilkS")
		)
		(fp_line
			(start -0.12065 -0.305054)
			(end -0.12065 -0.2794)
			(stroke
				(width 0.1)
				(type default)
			)
			(layer "F.Fab")
		)
		(fp_line
			(start -0.67945 -0.305054)
			(end -0.12065 -0.305054)
			(stroke
				(width 0.1)
				(type default)
			)
			(layer "F.Fab")
		)
		(fp_line
			(start 0.67945 -0.3048)
			(end 0.67945 0.3048)
			(stroke
				(width 0.1)
				(type default)
			)
			(layer "F.Fab")
		)
		(fp_line
			(start 0.12065 -0.3048)
			(end 0.67945 -0.3048)
			(stroke
				(width 0.1)
				(type default)
			)
			(layer "F.Fab")
		)
		(fp_line
			(start 0.12065 -0.2794)
			(end 0.12065 -0.3048)
			(stroke
				(width 0.1)
				(type default)
			)
			(layer "F.Fab")
		)
		(fp_line
			(start -0.12065 -0.2794)
			(end 0.12065 -0.2794)
			(stroke
				(width 0.1)
				(type default)
			)
			(layer "F.Fab")
		)
		(fp_line
			(start 0.120396 0.2794)
			(end -0.12065 0.2794)
			(stroke
				(width 0.1)
				(type default)
			)
			(layer "F.Fab")
		)
		(fp_line
			(start -0.12065 0.2794)
			(end -0.12065 0.3048)
			(stroke
				(width 0.1)
				(type default)
			)
			(layer "F.Fab")
		)
		(fp_line
			(start 0.67945 0.3048)
			(end 0.120396 0.3048)
			(stroke
				(width 0.1)
				(type default)
			)
			(layer "F.Fab")
		)
		(fp_line
			(start 0.120396 0.3048)
			(end 0.120396 0.2794)
			(stroke
				(width 0.1)
				(type default)
			)
			(layer "F.Fab")
		)
		(fp_line
			(start -0.12065 0.3048)
			(end -0.67945 0.3048)
			(stroke
				(width 0.1)
				(type default)
			)
			(layer "F.Fab")
		)
		(fp_line
			(start -0.67945 0.3048)
			(end -0.67945 -0.305054)
			(stroke
				(width 0.1)
				(type default)
			)
			(layer "F.Fab")
		)
		(pad "1" smd circle
			(at -0.40005 0 90)
			(size 0 0)
			(layers "F.Cu" "F.Mask" "F.Paste")
			(net "FM_AC_PWR_BTN_R_N")
		)
		(pad "2" smd circle
			(at 0.40005 0 90)
			(size 0 0)
			(layers "F.Cu" "F.Mask" "F.Paste")
			(net "FM_AC_PWR_BTN_PDB_N")
		)
	)
	(footprint ""
		(layer "F.Cu")
		(at 142.617444 -373.03583 -90)
		(property "Reference" "C769"
			(at 0 0 270)
			(layer "F.SilkS")
			(hide yes)
			(effects
				(font
					(size 1.27 1.27)
				)
			)
		)
		(property "Value" ""
			(at 0 0 270)
			(layer "F.Fab")
			(effects
				(font
					(size 1.27 1.27)
				)
			)
		)
		(duplicate_pad_numbers_are_jumpers no)
		(fp_line
			(start -0.299974 0.150114)
			(end -0.299974 -0.150114)
			(stroke
				(width 0.1)
				(type default)
			)
			(layer "F.Fab")
		)
		(fp_line
			(start 0.299974 0.150114)
			(end -0.299974 0.150114)
			(stroke
				(width 0.1)
				(type default)
			)
			(layer "F.Fab")
		)
		(fp_line
			(start -0.299974 -0.150114)
			(end 0.299974 -0.150114)
			(stroke
				(width 0.1)
				(type default)
			)
			(layer "F.Fab")
		)
		(fp_line
			(start 0.299974 -0.150114)
			(end 0.299974 0.150114)
			(stroke
				(width 0.1)
				(type default)
			)
			(layer "F.Fab")
		)
		(pad "1" smd rect
			(at -0.2667 0 270)
			(size 0.3048 0.381)
			(layers "F.Cu" "F.Mask" "F.Paste")
			(net "P5E_CPU1_P2_TX_C_DP<2>")
		)
		(pad "2" smd rect
			(at 0.2667 0 270)
			(size 0.3048 0.381)
			(layers "F.Cu" "F.Mask" "F.Paste")
			(net "P5E_CPU1_P2_TX_DP<2>")
		)
	)
	(footprint ""
		(layer "F.Cu")
		(at 362.265976 -256.012188 90)
		(property "Reference" "C2159"
			(at 0 0 90)
			(layer "F.SilkS")
			(hide yes)
			(effects
				(font
					(size 1.27 1.27)
				)
			)
		)
		(property "Value" ""
			(at 0 0 90)
			(layer "F.Fab")
			(effects
				(font
					(size 1.27 1.27)
				)
			)
		)
		(duplicate_pad_numbers_are_jumpers no)
		(fp_line
			(start 0.7874 -0.4064)
			(end 0.7874 0.4064)
			(stroke
				(width 0.1524)
				(type default)
			)
			(layer "F.SilkS")
		)
		(fp_line
			(start -0.7874 -0.4064)
			(end 0.7874 -0.4064)
			(stroke
				(width 0.1524)
				(type default)
			)
			(layer "F.SilkS")
		)
		(fp_line
			(start 0.7874 0.4064)
			(end -0.7874 0.4064)
			(stroke
				(width 0.1524)
				(type default)
			)
			(layer "F.SilkS")
		)
		(fp_line
			(start -0.7874 0.4064)
			(end -0.7874 -0.4064)
			(stroke
				(width 0.1524)
				(type default)
			)
			(layer "F.SilkS")
		)
		(fp_line
			(start -0.12065 -0.305054)
			(end -0.12065 -0.2794)
			(stroke
				(width 0.1)
				(type default)
			)
			(layer "F.Fab")
		)
		(fp_line
			(start -0.67945 -0.305054)
			(end -0.12065 -0.305054)
			(stroke
				(width 0.1)
				(type default)
			)
			(layer "F.Fab")
		)
		(fp_line
			(start 0.67945 -0.3048)
			(end 0.67945 0.3048)
			(stroke
				(width 0.1)
				(type default)
			)
			(layer "F.Fab")
		)
		(fp_line
			(start 0.12065 -0.3048)
			(end 0.67945 -0.3048)
			(stroke
				(width 0.1)
				(type default)
			)
			(layer "F.Fab")
		)
		(fp_line
			(start 0.12065 -0.2794)
			(end 0.12065 -0.3048)
			(stroke
				(width 0.1)
				(type default)
			)
			(layer "F.Fab")
		)
		(fp_line
			(start -0.12065 -0.2794)
			(end 0.12065 -0.2794)
			(stroke
				(width 0.1)
				(type default)
			)
			(layer "F.Fab")
		)
		(fp_line
			(start 0.120396 0.2794)
			(end -0.12065 0.2794)
			(stroke
				(width 0.1)
				(type default)
			)
			(layer "F.Fab")
		)
		(fp_line
			(start -0.12065 0.2794)
			(end -0.12065 0.3048)
			(stroke
				(width 0.1)
				(type default)
			)
			(layer "F.Fab")
		)
		(fp_line
			(start 0.67945 0.3048)
			(end 0.120396 0.3048)
			(stroke
				(width 0.1)
				(type default)
			)
			(layer "F.Fab")
		)
		(fp_line
			(start 0.120396 0.3048)
			(end 0.120396 0.2794)
			(stroke
				(width 0.1)
				(type default)
			)
			(layer "F.Fab")
		)
		(fp_line
			(start -0.12065 0.3048)
			(end -0.67945 0.3048)
			(stroke
				(width 0.1)
				(type default)
			)
			(layer "F.Fab")
		)
		(fp_line
			(start -0.67945 0.3048)
			(end -0.67945 -0.305054)
			(stroke
				(width 0.1)
				(type default)
			)
			(layer "F.Fab")
		)
		(pad "1" smd circle
			(at -0.40005 0 90)
			(size 0 0)
			(layers "F.Cu" "F.Mask" "F.Paste")
			(net "PVDDCR_SOC_P0")
		)
		(pad "2" smd circle
			(at 0.40005 0 90)
			(size 0 0)
			(layers "F.Cu" "F.Mask" "F.Paste")
			(net "GND")
		)
	)
	(footprint ""
		(layer "F.Cu")
		(at 205.232 -131.064)
		(property "Reference" "R490"
			(at 0 0 0)
			(layer "F.SilkS")
			(hide yes)
			(effects
				(font
					(size 1.27 1.27)
				)
			)
		)
		(property "Value" ""
			(at 0 0 0)
			(layer "F.Fab")
			(effects
				(font
					(size 1.27 1.27)
				)
			)
		)
		(duplicate_pad_numbers_are_jumpers no)
		(fp_line
			(start -0.7874 -0.4064)
			(end 0.7874 -0.4064)
			(stroke
				(width 0.1524)
				(type default)
			)
			(layer "F.SilkS")
		)
		(fp_line
			(start -0.7874 0.4064)
			(end -0.7874 -0.4064)
			(stroke
				(width 0.1524)
				(type default)
			)
			(layer "F.SilkS")
		)
		(fp_line
			(start 0.7874 -0.4064)
			(end 0.7874 0.4064)
			(stroke
				(width 0.1524)
				(type default)
			)
			(layer "F.SilkS")
		)
		(fp_line
			(start 0.7874 0.4064)
			(end -0.7874 0.4064)
			(stroke
				(width 0.1524)
				(type default)
			)
			(layer "F.SilkS")
		)
		(fp_line
			(start -0.67945 -0.305054)
			(end -0.12065 -0.305054)
			(stroke
				(width 0.1)
				(type default)
			)
			(layer "F.Fab")
		)
		(fp_line
			(start -0.67945 0.3048)
			(end -0.67945 -0.305054)
			(stroke
				(width 0.1)
				(type default)
			)
			(layer "F.Fab")
		)
		(fp_line
			(start -0.12065 -0.305054)
			(end -0.12065 -0.2794)
			(stroke
				(width 0.1)
				(type default)
			)
			(layer "F.Fab")
		)
		(fp_line
			(start -0.12065 -0.2794)
			(end 0.12065 -0.2794)
			(stroke
				(width 0.1)
				(type default)
			)
			(layer "F.Fab")
		)
		(fp_line
			(start -0.12065 0.2794)
			(end -0.12065 0.3048)
			(stroke
				(width 0.1)
				(type default)
			)
			(layer "F.Fab")
		)
		(fp_line
			(start -0.12065 0.3048)
			(end -0.67945 0.3048)
			(stroke
				(width 0.1)
				(type default)
			)
			(layer "F.Fab")
		)
		(fp_line
			(start 0.120396 0.2794)
			(end -0.12065 0.2794)
			(stroke
				(width 0.1)
				(type default)
			)
			(layer "F.Fab")
		)
		(fp_line
			(start 0.120396 0.3048)
			(end 0.120396 0.2794)
			(stroke
				(width 0.1)
				(type default)
			)
			(layer "F.Fab")
		)
		(fp_line
			(start 0.12065 -0.3048)
			(end 0.67945 -0.3048)
			(stroke
				(width 0.1)
				(type default)
			)
			(layer "F.Fab")
		)
		(fp_line
			(start 0.12065 -0.2794)
			(end 0.12065 -0.3048)
			(stroke
				(width 0.1)
				(type default)
			)
			(layer "F.Fab")
		)
		(fp_line
			(start 0.67945 -0.3048)
			(end 0.67945 0.3048)
			(stroke
				(width 0.1)
				(type default)
			)
			(layer "F.Fab")
		)
		(fp_line
			(start 0.67945 0.3048)
			(end 0.120396 0.3048)
			(stroke
				(width 0.1)
				(type default)
			)
			(layer "F.Fab")
		)
		(pad "1" smd circle
			(at -0.40005 0)
			(size 0 0)
			(layers "F.Cu" "F.Mask" "F.Paste")
			(net "PWRGD_P5V_R")
		)
		(pad "2" smd circle
			(at 0.40005 0)
			(size 0 0)
			(layers "F.Cu" "F.Mask" "F.Paste")
			(net "SW_P3V3_EN_R")
		)
	)
)
